FILE_TYPE = MACRO_DRAWING;
SET COLOR_WIRE YELLOW;
SET COLOR_PROP ORANGE;
SET COLOR_DOT WHITE;
SET COLOR_ARC YELLOW;
SET COLOR_BODY GREEN;
SET COLOR_NOTE PURPLE;
SET PROP_DISPLAY VALUE;
SET PAGE_NUMBER P61;
FORCEADD SN74LVC2G07DCKR..1
(-5000 2900);
FORCEPROP 1 LAST LOCATION U24
J 0
(-5175 3105);
DISPLAY 0.489362 (-5175 3105);
PAINT SKYBLUE (-5175 3105);
FORCEPROP 2 LAST $SEC 1
J 0
(-5175 3250);
DISPLAY 0.680851 (-5175 3250);
PAINT MONO (-5175 3250);
DISPLAY INVISIBLE (-5175 3250);
FORCEPROP 2 LAST CDS_SEC 1
J 0
(-5175 3250);
DISPLAY 0.680851 (-5175 3250);
DISPLAY INVISIBLE (-5175 3250);
FORCEPROP 2 LASTPIN (-5325 2950) $PN 1
J 2
(-5335 2960);
DISPLAY 0.489362 (-5335 2960);
PAINT MONO (-5335 2960);
FORCEPROP 2 LASTPIN (-4675 2950) $PN 6
J 0
(-4665 2960);
DISPLAY 0.489362 (-4665 2960);
PAINT MONO (-4665 2960);
FORCEPROP 2 LASTPIN (-5325 2850) $PN 3
J 2
(-5335 2860);
DISPLAY 0.489362 (-5335 2860);
PAINT MONO (-5335 2860);
FORCEPROP 2 LASTPIN (-4675 2850) $PN 4
J 0
(-4665 2860);
DISPLAY 0.489362 (-4665 2860);
PAINT MONO (-4665 2860);
FORCEPROP 2 LASTPIN (-5325 2900) $PN 2
J 2
(-5335 2910);
DISPLAY 0.489362 (-5335 2910);
PAINT MONO (-5335 2910);
FORCEPROP 2 LASTPIN (-4675 2900) $PN 5
J 0
(-4665 2910);
DISPLAY 0.489362 (-4665 2910);
PAINT MONO (-4665 2910);
FORCEPROP 1 LAST MATERIAL IC
J 0
(-5175 3010);
DISPLAY 0.489362 (-5175 3010);
PAINT SKYBLUE (-5175 3010);
FORCEPROP 2 LAST VALUE SN74LVC2G07DCKR
J 0
(-5175 3200);
DISPLAY 0.489362 (-5175 3200);
PAINT SKYBLUE (-5175 3200);
FORCEPROP 1 LAST PART_NUMBER AL002G07006
J 0
(-5175 3060);
DISPLAY 0.489362 (-5175 3060);
PAINT SKYBLUE (-5175 3060);
FORCEPROP 2 LAST PACK_TYPE SMLF
J 0
(-5175 3150);
DISPLAY 0.489362 (-5175 3150);
PAINT SKYBLUE (-5175 3150);
FORCEPROP 1 LAST NEEDS_NO_SIZE TRUE
J 0
(-5000 2900);
DISPLAY 0.468085 (-5000 2900);
PAINT GREEN (-5000 2900);
DISPLAY INVISIBLE (-5000 2900);
FORCEPROP 2 LAST CDS_LIB pure_quanta
J 0
(-5000 2900);
DISPLAY INVISIBLE (-5000 2900);
FORCEPROP 1 LAST PATH I17
J 0
(-4850 3005);
DISPLAY 0.723404 (-4850 3005);
PAINT GREEN (-4850 3005);
DISPLAY INVISIBLE (-4850 3005);
FORCEADD UNIVERSAL_GND..1
(-4450 3000);
FORCEPROP 3 LASTPIN (-4450 3050) SIG_NAME GND\g
J 0
(-4440 3060);
DISPLAY 0.659574 (-4440 3060);
PAINT MONO (-4440 3060);
DISPLAY INVISIBLE (-4440 3060);
FORCEPROP 2 LAST CDS_LIB pure_quanta_power
J 0
(-4450 3000);
DISPLAY INVISIBLE (-4450 3000);
FORCEPROP 1 LAST PATH I18
J 0
(-4375 3000);
DISPLAY 0.872340 (-4375 3000);
PAINT AQUA (-4375 3000);
DISPLAY INVISIBLE (-4375 3000);
FORCEPROP 1 LAST HDL_POWER GND
J 1
(-4425 2925);
DISPLAY 0.872340 (-4425 2925);
PAINT GREEN (-4425 2925);
DISPLAY INVISIBLE (-4425 2925);
FORCEADD UNIVERSAL_POWER..1
R 2
(-4525 3525);
FORCEPROP 3 LASTPIN (-4525 3475) SIG_NAME P3V3_STBY\g
J 0
(-4515 3485);
DISPLAY 0.659574 (-4515 3485);
PAINT MONO (-4515 3485);
DISPLAY INVISIBLE (-4515 3485);
FORCEPROP 1 LAST HDL_POWER P3V3_STBY
J 1
(-4525 3575);
DISPLAY 0.489362 (-4525 3575);
PAINT GREEN (-4525 3575);
FORCEPROP 2 LAST CDS_LIB pure_quanta_power
J 0
(-4525 3525);
DISPLAY INVISIBLE (-4525 3525);
FORCEPROP 1 LAST PATH I19
J 2
(-4575 3550);
DISPLAY 0.872340 (-4575 3550);
PAINT AQUA (-4575 3550);
DISPLAY INVISIBLE (-4575 3550);
FORCEADD Q_CAP..1
(-4450 3200);
FORCEPROP 1 LAST LOCATION C494
J 0
(-4400 3325);
DISPLAY 0.489362 (-4400 3325);
PAINT SKYBLUE (-4400 3325);
FORCEPROP 2 LAST $SEC 1
J 0
(-4400 3400);
DISPLAY 0.680851 (-4400 3400);
PAINT MONO (-4400 3400);
DISPLAY INVISIBLE (-4400 3400);
FORCEPROP 2 LAST CDS_SEC 1
J 0
(-4400 3400);
DISPLAY 0.680851 (-4400 3400);
DISPLAY INVISIBLE (-4400 3400);
FORCEPROP 1 LASTPIN (-4450 3300) $PN 1
J 0
(-4440 3280);
DISPLAY 0.489362 (-4440 3280);
PAINT MONO (-4440 3280);
FORCEPROP 1 LASTPIN (-4450 3100) $PN 2
J 0
(-4440 3080);
DISPLAY 0.489362 (-4440 3080);
PAINT MONO (-4440 3080);
FORCEPROP 1 LAST MATERIAL X7R
J 0
(-4400 3150);
DISPLAY 0.489362 (-4400 3150);
PAINT SKYBLUE (-4400 3150);
FORCEPROP 1 LAST TOLERANCE 10%
J 0
(-4400 3200);
DISPLAY 0.489362 (-4400 3200);
PAINT SKYBLUE (-4400 3200);
FORCEPROP 1 LAST VALUE 0.1UF
J 0
(-4400 3300);
DISPLAY 0.489362 (-4400 3300);
PAINT SKYBLUE (-4400 3300);
FORCEPROP 1 LAST VOLTAGE 25V
J 0
(-4400 3250);
DISPLAY 0.489362 (-4400 3250);
PAINT SKYBLUE (-4400 3250);
FORCEPROP 1 LAST PACK_TYPE 0402
J 0
(-4400 3100);
DISPLAY 0.489362 (-4400 3100);
PAINT SKYBLUE (-4400 3100);
FORCEPROP 2 LAST CDS_LIB pure_quanta
J 0
(-4450 3200);
DISPLAY INVISIBLE (-4450 3200);
FORCEPROP 1 LAST PATH I20
J 0
(-4400 3350);
DISPLAY 0.978723 (-4400 3350);
PAINT WHITE (-4400 3350);
DISPLAY INVISIBLE (-4400 3350);
FORCEPROP 1 LAST PART_NUMBER CH4104K1B00
J 0
(-4400 3050);
DISPLAY 0.489362 (-4400 3050);
PAINT SKYBLUE (-4400 3050);
DISPLAY INVISIBLE (-4400 3050);
FORCEADD OFFPAGE..4
R 2
(-6300 2950);
FORCEPROP 2 LAST $XR1 81 
J 0
(-6642 2950);
DISPLAY 0.638298 (-6642 2950);
PAINT MONO (-6642 2950);
FORCEPROP 2 LAST $XR0 115 
J 0
(-6552 2950);
DISPLAY 0.638298 (-6552 2950);
PAINT MONO (-6552 2950);
FORCEPROP 2 LAST PATH I21
J 0
(-6250 3025);
DISPLAY 0.680851 (-6250 3025);
DISPLAY INVISIBLE (-6250 3025);
FORCEPROP 1 LAST COMMENT_BODY TRUE
J 2
(-6275 2850);
DISPLAY 0.872340 (-6275 2850);
PAINT GREEN (-6275 2850);
DISPLAY INVISIBLE (-6275 2850);
FORCEPROP 1 LAST OFFPAGE TRUE
J 2
(-6625 2825);
DISPLAY 0.872340 (-6625 2825);
PAINT GREEN (-6625 2825);
DISPLAY INVISIBLE (-6625 2825);
FORCEPROP 2 LAST CDS_LIB standard
J 0
(-6300 2950);
DISPLAY INVISIBLE (-6300 2950);
FORCEADD OFFPAGE..4
R 2
(-6300 2850);
FORCEPROP 2 LAST $XR1 80 
J 0
(-6642 2850);
DISPLAY 0.638298 (-6642 2850);
PAINT MONO (-6642 2850);
FORCEPROP 2 LAST $XR0 115 
J 0
(-6552 2850);
DISPLAY 0.638298 (-6552 2850);
PAINT MONO (-6552 2850);
FORCEPROP 2 LAST PATH I22
J 0
(-6250 2925);
DISPLAY 0.680851 (-6250 2925);
DISPLAY INVISIBLE (-6250 2925);
FORCEPROP 1 LAST COMMENT_BODY TRUE
J 2
(-6275 2750);
DISPLAY 0.872340 (-6275 2750);
PAINT GREEN (-6275 2750);
DISPLAY INVISIBLE (-6275 2750);
FORCEPROP 1 LAST OFFPAGE TRUE
J 2
(-6625 2725);
DISPLAY 0.872340 (-6625 2725);
PAINT GREEN (-6625 2725);
DISPLAY INVISIBLE (-6625 2725);
FORCEPROP 2 LAST CDS_LIB standard
J 0
(-6300 2850);
DISPLAY INVISIBLE (-6300 2850);
FORCEADD OFFPAGE..5
R 2
(-3700 2950);
FORCEPROP 2 LAST $XR1 55 
J 0
(-3421 2950);
DISPLAY 0.638298 (-3421 2950);
PAINT MONO (-3421 2950);
FORCEPROP 2 LAST $XR0 61 
J 0
(-3511 2950);
DISPLAY 0.638298 (-3511 2950);
PAINT MONO (-3511 2950);
FORCEPROP 2 LAST PATH I23
J 0
(-3525 3025);
DISPLAY 0.680851 (-3525 3025);
DISPLAY INVISIBLE (-3525 3025);
FORCEPROP 1 LAST COMMENT_BODY TRUE
J 2
(-3800 2875);
DISPLAY 0.872340 (-3800 2875);
PAINT GREEN (-3800 2875);
DISPLAY INVISIBLE (-3800 2875);
FORCEPROP 1 LAST OFFPAGE TRUE
J 2
(-4025 2825);
DISPLAY 0.872340 (-4025 2825);
PAINT GREEN (-4025 2825);
DISPLAY INVISIBLE (-4025 2825);
FORCEPROP 2 LAST BOM_COST SYS_CLOCK
J 2
(-3900 3050);
DISPLAY 0.808511 (-3900 3050);
DISPLAY INVISIBLE (-3900 3050);
FORCEPROP 2 LAST CDS_LIB standard
J 0
(-3700 2950);
DISPLAY INVISIBLE (-3700 2950);
FORCEPROP 2 LAST ROOM DB2000_2_NVME
J 2
(-3900 3000);
DISPLAY 0.808511 (-3900 3000);
PAINT RED (-3900 3000);
DISPLAY INVISIBLE (-3900 3000);
FORCEADD OFFPAGE..5
R 2
(-3700 2850);
FORCEPROP 2 LAST $XR1 55 
J 0
(-3421 2850);
DISPLAY 0.638298 (-3421 2850);
PAINT MONO (-3421 2850);
FORCEPROP 2 LAST $XR0 61 
J 0
(-3511 2850);
DISPLAY 0.638298 (-3511 2850);
PAINT MONO (-3511 2850);
FORCEPROP 2 LAST PATH I24
J 0
(-3525 2925);
DISPLAY 0.680851 (-3525 2925);
DISPLAY INVISIBLE (-3525 2925);
FORCEPROP 1 LAST COMMENT_BODY TRUE
J 2
(-3800 2775);
DISPLAY 0.872340 (-3800 2775);
PAINT GREEN (-3800 2775);
DISPLAY INVISIBLE (-3800 2775);
FORCEPROP 1 LAST OFFPAGE TRUE
J 2
(-4025 2725);
DISPLAY 0.872340 (-4025 2725);
PAINT GREEN (-4025 2725);
DISPLAY INVISIBLE (-4025 2725);
FORCEPROP 2 LAST BOM_COST SYS_CLOCK
J 2
(-3900 2950);
DISPLAY 0.808511 (-3900 2950);
DISPLAY INVISIBLE (-3900 2950);
FORCEPROP 2 LAST CDS_LIB standard
J 0
(-3700 2850);
DISPLAY INVISIBLE (-3700 2850);
FORCEPROP 2 LAST ROOM DB2000_2_NVME
J 2
(-3900 2900);
DISPLAY 0.808511 (-3900 2900);
PAINT RED (-3900 2900);
DISPLAY INVISIBLE (-3900 2900);
FORCEADD UNIVERSAL_GND..1
R 5
(-5425 2900);
FORCEPROP 3 LASTPIN (-5375 2900) SIG_NAME GND\g
J 0
(-5365 2910);
DISPLAY 0.659574 (-5365 2910);
PAINT MONO (-5365 2910);
DISPLAY INVISIBLE (-5365 2910);
FORCEPROP 2 LAST CDS_LIB pure_quanta_power
J 0
(-5425 2900);
DISPLAY INVISIBLE (-5425 2900);
FORCEPROP 1 LAST PATH I25
R 3
J 0
(-5425 2825);
DISPLAY 0.872340 (-5425 2825);
PAINT AQUA (-5425 2825);
DISPLAY INVISIBLE (-5425 2825);
FORCEPROP 1 LAST HDL_POWER GND
R 3
J 1
(-5500 2875);
DISPLAY 0.872340 (-5500 2875);
PAINT GREEN (-5500 2875);
DISPLAY INVISIBLE (-5500 2875);
FORCEADD Q_RES..1
(-2525 3825);
FORCEPROP 1 LAST LOCATION R652
J 0
(-2775 3825);
DISPLAY 0.489362 (-2775 3825);
PAINT SKYBLUE (-2775 3825);
FORCEPROP 2 LAST $SEC 1
J 0
(-2575 4025);
DISPLAY 0.680851 (-2575 4025);
PAINT MONO (-2575 4025);
DISPLAY INVISIBLE (-2575 4025);
FORCEPROP 2 LAST CDS_SEC 1
J 0
(-2575 4025);
DISPLAY 0.680851 (-2575 4025);
DISPLAY INVISIBLE (-2575 4025);
FORCEPROP 1 LASTPIN (-2625 3825) $PN 1
J 0
(-2613 3837);
DISPLAY 0.489362 (-2613 3837);
PAINT MONO (-2613 3837);
FORCEPROP 1 LASTPIN (-2425 3825) $PN 2
J 0
(-2463 3837);
DISPLAY 0.489362 (-2463 3837);
PAINT MONO (-2463 3837);
FORCEPROP 1 LAST VALUE 4.7K
J 0
(-2400 3825);
DISPLAY 0.489362 (-2400 3825);
PAINT SKYBLUE (-2400 3825);
FORCEPROP 2 LAST CDS_LIB pure_quanta
J 0
(-2525 3825);
DISPLAY INVISIBLE (-2525 3825);
FORCEPROP 1 LAST PATH I26
J 0
(-2575 3975);
DISPLAY 0.978723 (-2575 3975);
PAINT WHITE (-2575 3975);
DISPLAY INVISIBLE (-2575 3975);
FORCEPROP 1 LAST WATTAGE 1/16W
J 2
(-2550 3675);
DISPLAY 0.510638 (-2550 3675);
PAINT SKYBLUE (-2550 3675);
DISPLAY INVISIBLE (-2550 3675);
FORCEPROP 1 LAST MATERIAL CHIP
J 0
(-2425 3800);
DISPLAY 0.489362 (-2425 3800);
PAINT SKYBLUE (-2425 3800);
DISPLAY INVISIBLE (-2425 3800);
FORCEPROP 1 LAST TOLERANCE 5%
J 0
(-2400 3825);
DISPLAY 0.510638 (-2400 3825);
PAINT SKYBLUE (-2400 3825);
DISPLAY INVISIBLE (-2400 3825);
FORCEPROP 1 LAST PART_NUMBER TMP_QCS24702JB38
J 0
(-2575 3925);
DISPLAY 0.510638 (-2575 3925);
PAINT SKYBLUE (-2575 3925);
DISPLAY INVISIBLE (-2575 3925);
FORCEPROP 1 LAST PACK_TYPE 0402LF
J 0
(-2275 3675);
DISPLAY 0.510638 (-2275 3675);
PAINT SKYBLUE (-2275 3675);
DISPLAY INVISIBLE (-2275 3675);
FORCEADD Q_RES..1
(-2525 3725);
FORCEPROP 1 LAST LOCATION R653
J 0
(-2775 3725);
DISPLAY 0.489362 (-2775 3725);
PAINT SKYBLUE (-2775 3725);
FORCEPROP 2 LAST $SEC 1
J 0
(-2575 3925);
DISPLAY 0.680851 (-2575 3925);
PAINT MONO (-2575 3925);
DISPLAY INVISIBLE (-2575 3925);
FORCEPROP 2 LAST CDS_SEC 1
J 0
(-2575 3925);
DISPLAY 0.680851 (-2575 3925);
DISPLAY INVISIBLE (-2575 3925);
FORCEPROP 1 LASTPIN (-2625 3725) $PN 1
J 0
(-2613 3737);
DISPLAY 0.489362 (-2613 3737);
PAINT MONO (-2613 3737);
FORCEPROP 1 LASTPIN (-2425 3725) $PN 2
J 0
(-2463 3737);
DISPLAY 0.489362 (-2463 3737);
PAINT MONO (-2463 3737);
FORCEPROP 1 LAST VALUE 4.7K
J 0
(-2400 3725);
DISPLAY 0.489362 (-2400 3725);
PAINT SKYBLUE (-2400 3725);
FORCEPROP 2 LAST CDS_LIB pure_quanta
J 0
(-2525 3725);
DISPLAY INVISIBLE (-2525 3725);
FORCEPROP 1 LAST PATH I27
J 0
(-2575 3875);
DISPLAY 0.978723 (-2575 3875);
PAINT WHITE (-2575 3875);
DISPLAY INVISIBLE (-2575 3875);
FORCEPROP 1 LAST WATTAGE 1/16W
J 2
(-2550 3575);
DISPLAY 0.510638 (-2550 3575);
PAINT SKYBLUE (-2550 3575);
DISPLAY INVISIBLE (-2550 3575);
FORCEPROP 1 LAST MATERIAL CHIP
J 0
(-2425 3700);
DISPLAY 0.489362 (-2425 3700);
PAINT SKYBLUE (-2425 3700);
DISPLAY INVISIBLE (-2425 3700);
FORCEPROP 1 LAST TOLERANCE 5%
J 0
(-2400 3725);
DISPLAY 0.510638 (-2400 3725);
PAINT SKYBLUE (-2400 3725);
DISPLAY INVISIBLE (-2400 3725);
FORCEPROP 1 LAST PART_NUMBER TMP_QCS24702JB38
J 0
(-2575 3825);
DISPLAY 0.510638 (-2575 3825);
PAINT SKYBLUE (-2575 3825);
DISPLAY INVISIBLE (-2575 3825);
FORCEPROP 1 LAST PACK_TYPE 0402LF
J 0
(-2275 3575);
DISPLAY 0.510638 (-2275 3575);
PAINT SKYBLUE (-2275 3575);
DISPLAY INVISIBLE (-2275 3575);
FORCEADD UNIVERSAL_POWER..1
R 2
(-2825 4100);
FORCEPROP 3 LASTPIN (-2825 4050) SIG_NAME PVDD18_S5_P1\g
J 0
(-2815 4060);
DISPLAY 0.659574 (-2815 4060);
PAINT MONO (-2815 4060);
DISPLAY INVISIBLE (-2815 4060);
FORCEPROP 1 LAST HDL_POWER PVDD18_S5_P1
J 1
(-2825 4150);
DISPLAY 0.489362 (-2825 4150);
PAINT GREEN (-2825 4150);
FORCEPROP 2 LAST CDS_LIB pure_quanta_power
J 0
(-2825 4100);
DISPLAY INVISIBLE (-2825 4100);
FORCEPROP 1 LAST PATH I28
J 2
(-2875 4125);
DISPLAY 0.872340 (-2875 4125);
PAINT AQUA (-2875 4125);
DISPLAY INVISIBLE (-2875 4125);
FORCEADD OFFPAGE..5
R 2
(-1450 3725);
FORCEPROP 2 LAST $XR1 55 
J 0
(-1171 3725);
DISPLAY 0.638298 (-1171 3725);
PAINT MONO (-1171 3725);
FORCEPROP 2 LAST $XR0 61 
J 0
(-1261 3725);
DISPLAY 0.638298 (-1261 3725);
PAINT MONO (-1261 3725);
FORCEPROP 2 LAST PATH I29
J 0
(-1275 3800);
DISPLAY 0.680851 (-1275 3800);
DISPLAY INVISIBLE (-1275 3800);
FORCEPROP 1 LAST COMMENT_BODY TRUE
J 2
(-1550 3650);
DISPLAY 0.872340 (-1550 3650);
PAINT GREEN (-1550 3650);
DISPLAY INVISIBLE (-1550 3650);
FORCEPROP 1 LAST OFFPAGE TRUE
J 2
(-1775 3600);
DISPLAY 0.872340 (-1775 3600);
PAINT GREEN (-1775 3600);
DISPLAY INVISIBLE (-1775 3600);
FORCEPROP 2 LAST CDS_LIB standard
J 0
(-1450 3725);
DISPLAY INVISIBLE (-1450 3725);
FORCEPROP 2 LAST BOM_COST SYS_CLOCK
J 2
(-1650 3825);
DISPLAY 0.808511 (-1650 3825);
DISPLAY INVISIBLE (-1650 3825);
FORCEPROP 2 LAST ROOM DB2000_2_NVME
J 2
(-1650 3775);
DISPLAY 0.808511 (-1650 3775);
PAINT RED (-1650 3775);
DISPLAY INVISIBLE (-1650 3775);
FORCEADD OFFPAGE..5
R 2
(-1450 3825);
FORCEPROP 2 LAST $XR1 55 
J 0
(-1171 3825);
DISPLAY 0.638298 (-1171 3825);
PAINT MONO (-1171 3825);
FORCEPROP 2 LAST $XR0 61 
J 0
(-1261 3825);
DISPLAY 0.638298 (-1261 3825);
PAINT MONO (-1261 3825);
FORCEPROP 2 LAST PATH I30
J 0
(-1275 3900);
DISPLAY 0.680851 (-1275 3900);
DISPLAY INVISIBLE (-1275 3900);
FORCEPROP 1 LAST COMMENT_BODY TRUE
J 2
(-1550 3750);
DISPLAY 0.872340 (-1550 3750);
PAINT GREEN (-1550 3750);
DISPLAY INVISIBLE (-1550 3750);
FORCEPROP 1 LAST OFFPAGE TRUE
J 2
(-1775 3700);
DISPLAY 0.872340 (-1775 3700);
PAINT GREEN (-1775 3700);
DISPLAY INVISIBLE (-1775 3700);
FORCEPROP 2 LAST CDS_LIB standard
J 0
(-1450 3825);
DISPLAY INVISIBLE (-1450 3825);
FORCEPROP 2 LAST BOM_COST SYS_CLOCK
J 2
(-1650 3925);
DISPLAY 0.808511 (-1650 3925);
DISPLAY INVISIBLE (-1650 3925);
FORCEPROP 2 LAST ROOM DB2000_2_NVME
J 2
(-1650 3875);
DISPLAY 0.808511 (-1650 3875);
PAINT RED (-1650 3875);
DISPLAY INVISIBLE (-1650 3875);
FORCEADD QUANTA_TITLE_BLOCK_C..1
(0 0);
FORCEPROP 0 LAST CDS_CON_LAST_MODIFIED Fri Mar 11 14:52:43 2022
J 0
(-1885 15);
DISPLAY INVISIBLE (-1885 15);
FORCEPROP 1 LAST CUSTOM_TXT_CDS <CON_LAST_MODIFIED>
J 0
(-1885 15);
DISPLAY 0.978723 (-1885 15);
FORCEPROP 2 LAST CUSTOM_TXT_CDS <XR_PAGE_TITLE>
J 0
(-7890 5250);
DISPLAY 0.638298 (-7890 5250);
PAINT PINK (-7890 5250);
DISPLAY INVISIBLE (-7890 5250);
FORCEPROP 1 LAST CUSTOM_TXT_CDS <NAME_2>
J 0
(-3175 50);
FORCEPROP 1 LAST CUSTOM_TXT_CDS <NAME_1>
J 0
(-3175 175);
FORCEPROP 1 LAST CUSTOM_TXT_CDS <Q_NUMBER>
J 0
(-1403 103);
DISPLAY 1.212766 (-1403 103);
FORCEPROP 1 LAST CUSTOM_TXT_CDS <Q_PROJ>
J 0
(-2382 102);
DISPLAY 1.212766 (-2382 102);
FORCEPROP 1 LAST CUSTOM_TXT_CDS <Q_REV>
J 0
(-184 103);
DISPLAY 1.212766 (-184 103);
FORCEPROP 1 LAST CUSTOM_TXT_CDS <CON_PAGE_NUM> OF <CON_TOTAL_PAGES>
J 0
(-446 18);
DISPLAY 0.978723 (-446 18);
FORCEPROP 1 LAST Q_TITLE CPU1 GLUE LOGIC
J 0
(-9300 75);
DISPLAY 2.446809 (-9300 75);
PAINT GREEN (-9300 75);
FORCEPROP 1 LAST Q_DEPT BU9
J 1
(-3763 49);
DISPLAY 1.957447 (-3763 49);
PAINT GREEN (-3763 49);
FORCEPROP 2 LAST PAGE_BORDER TRUE
J 0
(-7890 5250);
DISPLAY 0.638298 (-7890 5250);
PAINT PINK (-7890 5250);
DISPLAY INVISIBLE (-7890 5250);
FORCEPROP 2 LAST CDS_LIB pure_quanta
J 0
(0 0);
DISPLAY INVISIBLE (0 0);
FORCEPROP 1 LAST CDS_LMAN_SYM_OUTLINE -9475,6775,100,-125
J 0
(0 0);
DISPLAY 0.468085 (0 0);
PAINT GREEN (0 0);
DISPLAY INVISIBLE (0 0);
FORCEPROP 1 LAST COMMENT_BODY TRUE
J 0
(12 -13);
DISPLAY 0.978723 (12 -13);
PAINT GREEN (12 -13);
DISPLAY INVISIBLE (12 -13);
FORCEPROP 2 LAST CDS_XR_PAGE_TITLE CR-61 : @T6G_MB_LIB.T6G(SCH_1):PAGE61
J 0
(-7890 5250);
DISPLAY 0.638298 (-7890 5250);
PAINT PINK (-7890 5250);
DISPLAY INVISIBLE (-7890 5250);
WIRE 16 -1 (-4450 3100)(-4450 3050);
WIRE 16 -1 (-5375 2900)(-5325 2900);
WIRE 16 -1 (-6250 2950)(-5325 2950);
FORCEPROP 2 LAST SIG_NAME SLOT2_SKU_ID0
J 0
(-5900 2960);
DISPLAY 0.489362 (-5900 2960);
WIRE 16 -1 (-6250 2850)(-5325 2850);
FORCEPROP 2 LAST SIG_NAME SLOT2_SKU_ID1
J 0
(-5900 2860);
DISPLAY 0.489362 (-5900 2860);
WIRE 16 -1 (-4675 2900)(-4525 2900);
WIRE 16 -1 (-4525 3375)(-4525 2900);
WIRE 16 -1 (-4450 3375)(-4525 3375);
WIRE 16 -1 (-4525 3475)(-4525 3375);
WIRE 16 -1 (-4450 3300)(-4450 3375);
WIRE 16 -1 (-4675 2950)(-3750 2950);
FORCEPROP 2 LAST SIG_NAME SLOT2_BUF_SKU_ID0
J 0
(-4325 2960);
DISPLAY 0.489362 (-4325 2960);
WIRE 16 -1 (-4675 2850)(-3750 2850);
FORCEPROP 2 LAST SIG_NAME SLOT2_BUF_SKU_ID1
J 0
(-4325 2860);
DISPLAY 0.489362 (-4325 2860);
WIRE 16 -1 (-2825 3725)(-2625 3725);
WIRE 16 -1 (-2825 3825)(-2825 3725);
WIRE 16 -1 (-2825 4050)(-2825 3825);
WIRE 16 -1 (-2825 3825)(-2625 3825);
WIRE 16 -1 (-2425 3725)(-1500 3725);
FORCEPROP 2 LAST SIG_NAME SLOT2_BUF_SKU_ID1
J 0
(-2075 3735);
DISPLAY 0.489362 (-2075 3735);
WIRE 16 -1 (-2425 3825)(-1500 3825);
FORCEPROP 2 LAST SIG_NAME SLOT2_BUF_SKU_ID0
J 0
(-2075 3835);
DISPLAY 0.489362 (-2075 3835);
DOT 1 (-2825 3825);
DOT 1 (-4525 3375);
QUIT
